(kicad_pcb
	(version 20260206)
	(generator "pcbnew")
	(generator_version "10.0")
	(general
		(thickness 1.6)
		(legacy_teardrops no)
	)
	(paper "A4")
	(title_block
		(title "01162023_DA0F0TEBIF0_F0T_Expander_BD_F_brd_V02_OCP.brd")
		(comment 1 "Grand Teton / footprints 144-149 of 9728")
	)
	(layers
		(0 "F.Cu" signal "TOP")
		(4 "In1.Cu" signal "GND")
		(6 "In2.Cu" signal "VCC")
		(8 "In3.Cu" signal "VCC1")
		(10 "In4.Cu" signal "GND1")
		(12 "In5.Cu" signal "IN1")
		(14 "In6.Cu" signal "GND2")
		(16 "In7.Cu" signal "IN2")
		(18 "In8.Cu" signal "GND3")
		(20 "In9.Cu" signal "IN3")
		(22 "In10.Cu" signal "GND4")
		(24 "In11.Cu" signal "IN4")
		(26 "In12.Cu" signal "GND5")
		(28 "In13.Cu" signal "IN5")
		(30 "In14.Cu" signal "GND6")
		(32 "In15.Cu" signal "IN6")
		(34 "In16.Cu" signal "GND7")
		(2 "B.Cu" signal "BOTTOM")
		(9 "F.Adhes" user "F.Adhesive")
		(11 "B.Adhes" user "B.Adhesive")
		(13 "F.Paste" user "Package Geometry/Pastemask Top")
		(15 "B.Paste" user "Package Geometry/Pastemask Bottom")
		(5 "F.SilkS" user "Ref Des/Silkscreen Top")
		(7 "B.SilkS" user "Ref Des/Silkscreen Bottom")
		(1 "F.Mask" user "Board Geometry/Soldermask Top")
		(3 "B.Mask" user "Board Geometry/Soldermask Bottom")
		(17 "Dwgs.User" user "User.Drawings")
		(19 "Cmts.User" user "User.Comments")
		(21 "Eco1.User" user "User.Eco1")
		(23 "Eco2.User" user "User.Eco2")
		(25 "Edge.Cuts" user "Board Geometry/Outline")
		(27 "Margin" user)
		(31 "F.CrtYd" user "Package Geometry/Place Bound Top")
		(29 "B.CrtYd" user "Package Geometry/Place Bound Bottom")
		(35 "F.Fab" user "Ref Des/Assembly Top")
		(33 "B.Fab" user "Ref Des/Assembly Bottom")
	)
	(footprint ""
		(layer "F.Cu")
		(at 112.128046 -35.876738)
		(property "Reference" "R6058"
			(at 0 0 0)
			(layer "F.SilkS")
			(hide yes)
			(effects
				(font
					(size 1.27 1.27)
				)
			)
		)
		(property "Value" ""
			(at 0 0 0)
			(layer "F.Fab")
			(effects
				(font
					(size 1.27 1.27)
				)
			)
		)
		(duplicate_pad_numbers_are_jumpers no)
		(fp_line
			(start -0.7874 -0.4064)
			(end 0.7874 -0.4064)
			(stroke
				(width 0.1524)
				(type default)
			)
			(layer "F.SilkS")
		)
		(fp_line
			(start -0.7874 0.4064)
			(end -0.7874 -0.4064)
			(stroke
				(width 0.1524)
				(type default)
			)
			(layer "F.SilkS")
		)
		(fp_line
			(start 0.7874 -0.4064)
			(end 0.7874 0.4064)
			(stroke
				(width 0.1524)
				(type default)
			)
			(layer "F.SilkS")
		)
		(fp_line
			(start 0.7874 0.4064)
			(end -0.7874 0.4064)
			(stroke
				(width 0.1524)
				(type default)
			)
			(layer "F.SilkS")
		)
		(fp_line
			(start -0.67945 -0.305054)
			(end -0.12065 -0.305054)
			(stroke
				(width 0.1)
				(type default)
			)
			(layer "F.Fab")
		)
		(fp_line
			(start -0.67945 0.3048)
			(end -0.67945 -0.305054)
			(stroke
				(width 0.1)
				(type default)
			)
			(layer "F.Fab")
		)
		(fp_line
			(start -0.12065 -0.305054)
			(end -0.12065 -0.2794)
			(stroke
				(width 0.1)
				(type default)
			)
			(layer "F.Fab")
		)
		(fp_line
			(start -0.12065 -0.2794)
			(end 0.12065 -0.2794)
			(stroke
				(width 0.1)
				(type default)
			)
			(layer "F.Fab")
		)
		(fp_line
			(start -0.12065 0.2794)
			(end -0.12065 0.3048)
			(stroke
				(width 0.1)
				(type default)
			)
			(layer "F.Fab")
		)
		(fp_line
			(start -0.12065 0.3048)
			(end -0.67945 0.3048)
			(stroke
				(width 0.1)
				(type default)
			)
			(layer "F.Fab")
		)
		(fp_line
			(start 0.120396 0.2794)
			(end -0.12065 0.2794)
			(stroke
				(width 0.1)
				(type default)
			)
			(layer "F.Fab")
		)
		(fp_line
			(start 0.120396 0.3048)
			(end 0.120396 0.2794)
			(stroke
				(width 0.1)
				(type default)
			)
			(layer "F.Fab")
		)
		(fp_line
			(start 0.12065 -0.3048)
			(end 0.67945 -0.3048)
			(stroke
				(width 0.1)
				(type default)
			)
			(layer "F.Fab")
		)
		(fp_line
			(start 0.12065 -0.2794)
			(end 0.12065 -0.3048)
			(stroke
				(width 0.1)
				(type default)
			)
			(layer "F.Fab")
		)
		(fp_line
			(start 0.67945 -0.3048)
			(end 0.67945 0.3048)
			(stroke
				(width 0.1)
				(type default)
			)
			(layer "F.Fab")
		)
		(fp_line
			(start 0.67945 0.3048)
			(end 0.120396 0.3048)
			(stroke
				(width 0.1)
				(type default)
			)
			(layer "F.Fab")
		)
		(pad "1" smd circle
			(at -0.40005 0)
			(size 0 0)
			(layers "F.Cu" "F.Mask" "F.Paste")
			(net "PWRGD_P3V3_SSD4_D")
		)
		(pad "2" smd circle
			(at 0.40005 0)
			(size 0 0)
			(layers "F.Cu" "F.Mask" "F.Paste")
			(net "PWRGD_P3V3_SSD4_R")
		)
	)
	(footprint ""
		(layer "F.Cu")
		(at 224.856294 -184.703212)
		(property "Reference" "C2185"
			(at 0 0 0)
			(layer "F.SilkS")
			(hide yes)
			(effects
				(font
					(size 1.27 1.27)
				)
			)
		)
		(property "Value" ""
			(at 0 0 0)
			(layer "F.Fab")
			(effects
				(font
					(size 1.27 1.27)
				)
			)
		)
		(duplicate_pad_numbers_are_jumpers no)
		(fp_line
			(start -0.7874 -0.4064)
			(end 0.7874 -0.4064)
			(stroke
				(width 0.1524)
				(type default)
			)
			(layer "F.SilkS")
		)
		(fp_line
			(start -0.7874 0.4064)
			(end -0.7874 -0.4064)
			(stroke
				(width 0.1524)
				(type default)
			)
			(layer "F.SilkS")
		)
		(fp_line
			(start 0.7874 -0.4064)
			(end 0.7874 0.4064)
			(stroke
				(width 0.1524)
				(type default)
			)
			(layer "F.SilkS")
		)
		(fp_line
			(start 0.7874 0.4064)
			(end -0.7874 0.4064)
			(stroke
				(width 0.1524)
				(type default)
			)
			(layer "F.SilkS")
		)
		(fp_line
			(start -0.67945 -0.305054)
			(end -0.12065 -0.305054)
			(stroke
				(width 0.1)
				(type default)
			)
			(layer "F.Fab")
		)
		(fp_line
			(start -0.67945 0.3048)
			(end -0.67945 -0.305054)
			(stroke
				(width 0.1)
				(type default)
			)
			(layer "F.Fab")
		)
		(fp_line
			(start -0.12065 -0.305054)
			(end -0.12065 -0.2794)
			(stroke
				(width 0.1)
				(type default)
			)
			(layer "F.Fab")
		)
		(fp_line
			(start -0.12065 -0.2794)
			(end 0.12065 -0.2794)
			(stroke
				(width 0.1)
				(type default)
			)
			(layer "F.Fab")
		)
		(fp_line
			(start -0.12065 0.2794)
			(end -0.12065 0.3048)
			(stroke
				(width 0.1)
				(type default)
			)
			(layer "F.Fab")
		)
		(fp_line
			(start -0.12065 0.3048)
			(end -0.67945 0.3048)
			(stroke
				(width 0.1)
				(type default)
			)
			(layer "F.Fab")
		)
		(fp_line
			(start 0.120396 0.2794)
			(end -0.12065 0.2794)
			(stroke
				(width 0.1)
				(type default)
			)
			(layer "F.Fab")
		)
		(fp_line
			(start 0.120396 0.3048)
			(end 0.120396 0.2794)
			(stroke
				(width 0.1)
				(type default)
			)
			(layer "F.Fab")
		)
		(fp_line
			(start 0.12065 -0.3048)
			(end 0.67945 -0.3048)
			(stroke
				(width 0.1)
				(type default)
			)
			(layer "F.Fab")
		)
		(fp_line
			(start 0.12065 -0.2794)
			(end 0.12065 -0.3048)
			(stroke
				(width 0.1)
				(type default)
			)
			(layer "F.Fab")
		)
		(fp_line
			(start 0.67945 -0.3048)
			(end 0.67945 0.3048)
			(stroke
				(width 0.1)
				(type default)
			)
			(layer "F.Fab")
		)
		(fp_line
			(start 0.67945 0.3048)
			(end 0.120396 0.3048)
			(stroke
				(width 0.1)
				(type default)
			)
			(layer "F.Fab")
		)
		(pad "1" smd circle
			(at -0.40005 0)
			(size 0 0)
			(layers "F.Cu" "F.Mask" "F.Paste")
			(net "P3V3_AUX")
		)
		(pad "2" smd circle
			(at 0.40005 0)
			(size 0 0)
			(layers "F.Cu" "F.Mask" "F.Paste")
			(net "GND")
		)
	)
	(footprint ""
		(layer "F.Cu")
		(at 265.487658 -288.419032)
		(property "Reference" "C3403"
			(at 0 0 0)
			(layer "F.SilkS")
			(hide yes)
			(effects
				(font
					(size 1.27 1.27)
				)
			)
		)
		(property "Value" ""
			(at 0 0 0)
			(layer "F.Fab")
			(effects
				(font
					(size 1.27 1.27)
				)
			)
		)
		(duplicate_pad_numbers_are_jumpers no)
		(fp_line
			(start -1.2954 -0.5842)
			(end 1.2954 -0.5842)
			(stroke
				(width 0.1524)
				(type default)
			)
			(layer "F.SilkS")
		)
		(fp_line
			(start -1.2954 0.5842)
			(end -1.2954 -0.5842)
			(stroke
				(width 0.1524)
				(type default)
			)
			(layer "F.SilkS")
		)
		(fp_line
			(start 1.2954 -0.5842)
			(end 1.2954 0.5842)
			(stroke
				(width 0.1524)
				(type default)
			)
			(layer "F.SilkS")
		)
		(fp_line
			(start 1.2954 0.5842)
			(end -1.2954 0.5842)
			(stroke
				(width 0.1524)
				(type default)
			)
			(layer "F.SilkS")
		)
		(fp_line
			(start -1.1938 -0.4064)
			(end -0.8636 -0.4064)
			(stroke
				(width 0.1)
				(type default)
			)
			(layer "F.Fab")
		)
		(fp_line
			(start -1.1938 0.4064)
			(end -1.1938 -0.4064)
			(stroke
				(width 0.1)
				(type default)
			)
			(layer "F.Fab")
		)
		(fp_line
			(start -0.8636 -0.4572)
			(end 0.8636 -0.4572)
			(stroke
				(width 0.1)
				(type default)
			)
			(layer "F.Fab")
		)
		(fp_line
			(start -0.8636 -0.4064)
			(end -0.8636 -0.4572)
			(stroke
				(width 0.1)
				(type default)
			)
			(layer "F.Fab")
		)
		(fp_line
			(start -0.8636 0.4064)
			(end -1.1938 0.4064)
			(stroke
				(width 0.1)
				(type default)
			)
			(layer "F.Fab")
		)
		(fp_line
			(start -0.8636 0.4572)
			(end -0.8636 0.4064)
			(stroke
				(width 0.1)
				(type default)
			)
			(layer "F.Fab")
		)
		(fp_line
			(start 0.8636 -0.4572)
			(end 0.8636 -0.4064)
			(stroke
				(width 0.1)
				(type default)
			)
			(layer "F.Fab")
		)
		(fp_line
			(start 0.8636 -0.4064)
			(end 1.1938 -0.4064)
			(stroke
				(width 0.1)
				(type default)
			)
			(layer "F.Fab")
		)
		(fp_line
			(start 0.8636 0.4064)
			(end 0.8636 0.4572)
			(stroke
				(width 0.1)
				(type default)
			)
			(layer "F.Fab")
		)
		(fp_line
			(start 0.8636 0.4572)
			(end -0.8636 0.4572)
			(stroke
				(width 0.1)
				(type default)
			)
			(layer "F.Fab")
		)
		(fp_line
			(start 1.1938 -0.4064)
			(end 1.1938 0.4064)
			(stroke
				(width 0.1)
				(type default)
			)
			(layer "F.Fab")
		)
		(fp_line
			(start 1.1938 0.4064)
			(end 0.8636 0.4064)
			(stroke
				(width 0.1)
				(type default)
			)
			(layer "F.Fab")
		)
		(pad "1" smd rect
			(at -0.7366 0 270)
			(size 0.7112 0.8128)
			(layers "F.Cu" "F.Mask" "F.Paste")
			(net "PCEPLL6_VDDA18_PEX2")
		)
		(pad "2" smd rect
			(at 0.7366 0 270)
			(size 0.7112 0.8128)
			(layers "F.Cu" "F.Mask" "F.Paste")
			(net "GND")
		)
	)
	(footprint ""
		(layer "F.Cu")
		(at 261.05612 -32.848042 -90)
		(property "Reference" "R6079"
			(at 0 0 270)
			(layer "F.SilkS")
			(hide yes)
			(effects
				(font
					(size 1.27 1.27)
				)
			)
		)
		(property "Value" ""
			(at 0 0 270)
			(layer "F.Fab")
			(effects
				(font
					(size 1.27 1.27)
				)
			)
		)
		(duplicate_pad_numbers_are_jumpers no)
		(fp_line
			(start -0.7874 0.4064)
			(end -0.7874 -0.4064)
			(stroke
				(width 0.1524)
				(type default)
			)
			(layer "F.SilkS")
		)
		(fp_line
			(start 0.7874 0.4064)
			(end -0.7874 0.4064)
			(stroke
				(width 0.1524)
				(type default)
			)
			(layer "F.SilkS")
		)
		(fp_line
			(start -0.7874 -0.4064)
			(end 0.7874 -0.4064)
			(stroke
				(width 0.1524)
				(type default)
			)
			(layer "F.SilkS")
		)
		(fp_line
			(start 0.7874 -0.4064)
			(end 0.7874 0.4064)
			(stroke
				(width 0.1524)
				(type default)
			)
			(layer "F.SilkS")
		)
		(fp_line
			(start -0.67945 0.3048)
			(end -0.67945 -0.305054)
			(stroke
				(width 0.1)
				(type default)
			)
			(layer "F.Fab")
		)
		(fp_line
			(start -0.12065 0.3048)
			(end -0.67945 0.3048)
			(stroke
				(width 0.1)
				(type default)
			)
			(layer "F.Fab")
		)
		(fp_line
			(start 0.120396 0.3048)
			(end 0.120396 0.2794)
			(stroke
				(width 0.1)
				(type default)
			)
			(layer "F.Fab")
		)
		(fp_line
			(start 0.67945 0.3048)
			(end 0.120396 0.3048)
			(stroke
				(width 0.1)
				(type default)
			)
			(layer "F.Fab")
		)
		(fp_line
			(start -0.12065 0.2794)
			(end -0.12065 0.3048)
			(stroke
				(width 0.1)
				(type default)
			)
			(layer "F.Fab")
		)
		(fp_line
			(start 0.120396 0.2794)
			(end -0.12065 0.2794)
			(stroke
				(width 0.1)
				(type default)
			)
			(layer "F.Fab")
		)
		(fp_line
			(start -0.12065 -0.2794)
			(end 0.12065 -0.2794)
			(stroke
				(width 0.1)
				(type default)
			)
			(layer "F.Fab")
		)
		(fp_line
			(start 0.12065 -0.2794)
			(end 0.12065 -0.3048)
			(stroke
				(width 0.1)
				(type default)
			)
			(layer "F.Fab")
		)
		(fp_line
			(start 0.12065 -0.3048)
			(end 0.67945 -0.3048)
			(stroke
				(width 0.1)
				(type default)
			)
			(layer "F.Fab")
		)
		(fp_line
			(start 0.67945 -0.3048)
			(end 0.67945 0.3048)
			(stroke
				(width 0.1)
				(type default)
			)
			(layer "F.Fab")
		)
		(fp_line
			(start -0.67945 -0.305054)
			(end -0.12065 -0.305054)
			(stroke
				(width 0.1)
				(type default)
			)
			(layer "F.Fab")
		)
		(fp_line
			(start -0.12065 -0.305054)
			(end -0.12065 -0.2794)
			(stroke
				(width 0.1)
				(type default)
			)
			(layer "F.Fab")
		)
		(pad "1" smd circle
			(at -0.40005 0 270)
			(size 0 0)
			(layers "F.Cu" "F.Mask" "F.Paste")
			(net "SSD9_AUX_P3V3_EN_R")
		)
		(pad "2" smd circle
			(at 0.40005 0 270)
			(size 0 0)
			(layers "F.Cu" "F.Mask" "F.Paste")
			(net "P3V3_SSD9_CO_EN")
		)
	)
	(footprint ""
		(layer "F.Cu")
		(at 123.31319 -110.722918 -90)
		(property "Reference" "R5825"
			(at 0 0 270)
			(layer "F.SilkS")
			(hide yes)
			(effects
				(font
					(size 1.27 1.27)
				)
			)
		)
		(property "Value" ""
			(at 0 0 270)
			(layer "F.Fab")
			(effects
				(font
					(size 1.27 1.27)
				)
			)
		)
		(duplicate_pad_numbers_are_jumpers no)
		(fp_line
			(start -0.7874 0.4064)
			(end -0.7874 -0.4064)
			(stroke
				(width 0.1524)
				(type default)
			)
			(layer "F.SilkS")
		)
		(fp_line
			(start 0.7874 0.4064)
			(end -0.7874 0.4064)
			(stroke
				(width 0.1524)
				(type default)
			)
			(layer "F.SilkS")
		)
		(fp_line
			(start -0.7874 -0.4064)
			(end 0.7874 -0.4064)
			(stroke
				(width 0.1524)
				(type default)
			)
			(layer "F.SilkS")
		)
		(fp_line
			(start 0.7874 -0.4064)
			(end 0.7874 0.4064)
			(stroke
				(width 0.1524)
				(type default)
			)
			(layer "F.SilkS")
		)
		(fp_line
			(start -0.67945 0.3048)
			(end -0.67945 -0.305054)
			(stroke
				(width 0.1)
				(type default)
			)
			(layer "F.Fab")
		)
		(fp_line
			(start -0.12065 0.3048)
			(end -0.67945 0.3048)
			(stroke
				(width 0.1)
				(type default)
			)
			(layer "F.Fab")
		)
		(fp_line
			(start 0.120396 0.3048)
			(end 0.120396 0.2794)
			(stroke
				(width 0.1)
				(type default)
			)
			(layer "F.Fab")
		)
		(fp_line
			(start 0.67945 0.3048)
			(end 0.120396 0.3048)
			(stroke
				(width 0.1)
				(type default)
			)
			(layer "F.Fab")
		)
		(fp_line
			(start -0.12065 0.2794)
			(end -0.12065 0.3048)
			(stroke
				(width 0.1)
				(type default)
			)
			(layer "F.Fab")
		)
		(fp_line
			(start 0.120396 0.2794)
			(end -0.12065 0.2794)
			(stroke
				(width 0.1)
				(type default)
			)
			(layer "F.Fab")
		)
		(fp_line
			(start -0.12065 -0.2794)
			(end 0.12065 -0.2794)
			(stroke
				(width 0.1)
				(type default)
			)
			(layer "F.Fab")
		)
		(fp_line
			(start 0.12065 -0.2794)
			(end 0.12065 -0.3048)
			(stroke
				(width 0.1)
				(type default)
			)
			(layer "F.Fab")
		)
		(fp_line
			(start 0.12065 -0.3048)
			(end 0.67945 -0.3048)
			(stroke
				(width 0.1)
				(type default)
			)
			(layer "F.Fab")
		)
		(fp_line
			(start 0.67945 -0.3048)
			(end 0.67945 0.3048)
			(stroke
				(width 0.1)
				(type default)
			)
			(layer "F.Fab")
		)
		(fp_line
			(start -0.67945 -0.305054)
			(end -0.12065 -0.305054)
			(stroke
				(width 0.1)
				(type default)
			)
			(layer "F.Fab")
		)
		(fp_line
			(start -0.12065 -0.305054)
			(end -0.12065 -0.2794)
			(stroke
				(width 0.1)
				(type default)
			)
			(layer "F.Fab")
		)
		(pad "1" smd circle
			(at -0.40005 0 270)
			(size 0 0)
			(layers "F.Cu" "F.Mask" "F.Paste")
			(net "P3V3")
		)
		(pad "2" smd circle
			(at 0.40005 0 270)
			(size 0 0)
			(layers "F.Cu" "F.Mask" "F.Paste")
			(net "PWRGD_P3V3_D")
		)
	)
	(footprint ""
		(layer "F.Cu")
		(at 359.85831 -253.178564 180)
		(property "Reference" "PR124"
			(at 0 0 180)
			(layer "F.SilkS")
			(hide yes)
			(effects
				(font
					(size 1.27 1.27)
				)
			)
		)
		(property "Value" ""
			(at 0 0 180)
			(layer "F.Fab")
			(effects
				(font
					(size 1.27 1.27)
				)
			)
		)
		(duplicate_pad_numbers_are_jumpers no)
		(fp_line
			(start 0.7874 0.4064)
			(end -0.7874 0.4064)
			(stroke
				(width 0.1524)
				(type default)
			)
			(layer "F.SilkS")
		)
		(fp_line
			(start 0.7874 -0.4064)
			(end 0.7874 0.4064)
			(stroke
				(width 0.1524)
				(type default)
			)
			(layer "F.SilkS")
		)
		(fp_line
			(start -0.7874 0.4064)
			(end -0.7874 -0.4064)
			(stroke
				(width 0.1524)
				(type default)
			)
			(layer "F.SilkS")
		)
		(fp_line
			(start -0.7874 -0.4064)
			(end 0.7874 -0.4064)
			(stroke
				(width 0.1524)
				(type default)
			)
			(layer "F.SilkS")
		)
		(fp_line
			(start 0.67945 0.3048)
			(end 0.120396 0.3048)
			(stroke
				(width 0.1)
				(type default)
			)
			(layer "F.Fab")
		)
		(fp_line
			(start 0.67945 -0.3048)
			(end 0.67945 0.3048)
			(stroke
				(width 0.1)
				(type default)
			)
			(layer "F.Fab")
		)
		(fp_line
			(start 0.12065 -0.2794)
			(end 0.12065 -0.3048)
			(stroke
				(width 0.1)
				(type default)
			)
			(layer "F.Fab")
		)
		(fp_line
			(start 0.12065 -0.3048)
			(end 0.67945 -0.3048)
			(stroke
				(width 0.1)
				(type default)
			)
			(layer "F.Fab")
		)
		(fp_line
			(start 0.120396 0.3048)
			(end 0.120396 0.2794)
			(stroke
				(width 0.1)
				(type default)
			)
			(layer "F.Fab")
		)
		(fp_line
			(start 0.120396 0.2794)
			(end -0.12065 0.2794)
			(stroke
				(width 0.1)
				(type default)
			)
			(layer "F.Fab")
		)
		(fp_line
			(start -0.12065 0.3048)
			(end -0.67945 0.3048)
			(stroke
				(width 0.1)
				(type default)
			)
			(layer "F.Fab")
		)
		(fp_line
			(start -0.12065 0.2794)
			(end -0.12065 0.3048)
			(stroke
				(width 0.1)
				(type default)
			)
			(layer "F.Fab")
		)
		(fp_line
			(start -0.12065 -0.2794)
			(end 0.12065 -0.2794)
			(stroke
				(width 0.1)
				(type default)
			)
			(layer "F.Fab")
		)
		(fp_line
			(start -0.12065 -0.305054)
			(end -0.12065 -0.2794)
			(stroke
				(width 0.1)
				(type default)
			)
			(layer "F.Fab")
		)
		(fp_line
			(start -0.67945 0.3048)
			(end -0.67945 -0.305054)
			(stroke
				(width 0.1)
				(type default)
			)
			(layer "F.Fab")
		)
		(fp_line
			(start -0.67945 -0.305054)
			(end -0.12065 -0.305054)
			(stroke
				(width 0.1)
				(type default)
			)
			(layer "F.Fab")
		)
		(pad "1" smd circle
			(at -0.40005 0 180)
			(size 0 0)
			(layers "F.Cu" "F.Mask" "F.Paste")
			(net "P3V3_AUX")
		)
		(pad "2" smd circle
			(at 0.40005 0 180)
			(size 0 0)
			(layers "F.Cu" "F.Mask" "F.Paste")
			(net "P0V8_PEX2_SMBALERT")
		)
	)
)
